# T6G (Grand Teton) — schematic netlist excerpt (pin names and nets, part order shuffled) for the footprints in the layout excerpt that follows; sources: Cadence DE-HDL packaged netlist, KiCad conversion of 04192023_DAF0TMB3IC0_F0TG_MB_C_brd_V02_OCP.brd

R1043  Q_RES  0 5% CHIP  pkg 0201LF  page 288 : A = NCF_A1_CPU0_P1_GND ; B = GND
R10  Q_RES  10K 1% CHIP  pkg 0402LF  page 83 : A = FM_I3C_CPU0_MUX0_OE_N ; B = GND
PC2185  Q_CAP  0.068UF 16V 10% X7R  pkg 0402  page 263 : A = HSC_SS ; B = AGND_HSC

(kicad_pcb
	(version 20260206)
	(generator "pcbnew")
	(generator_version "10.0")
	(general
		(thickness 1.6)
		(legacy_teardrops no)
	)
	(paper "A4")
	(title_block
		(title "04192023_DAF0TMB3IC0_F0TG_MB_C_brd_V02_OCP.brd")
		(comment 1 "Grand Teton / footprints 442-444 of 8354")
	)
	(layers
		(0 "F.Cu" signal "TOP")
		(4 "In1.Cu" signal "GND")
		(6 "In2.Cu" signal "IN1")
		(8 "In3.Cu" signal "GND1")
		(10 "In4.Cu" signal "IN2")
		(12 "In5.Cu" signal "GND2")
		(14 "In6.Cu" signal "IN3")
		(16 "In7.Cu" signal "GND3")
		(18 "In8.Cu" signal "VCC")
		(20 "In9.Cu" signal "VCC1")
		(22 "In10.Cu" signal "GND4")
		(24 "In11.Cu" signal "IN4")
		(26 "In12.Cu" signal "GND5")
		(28 "In13.Cu" signal "IN5")
		(30 "In14.Cu" signal "GND6")
		(32 "In15.Cu" signal "IN6")
		(34 "In16.Cu" signal "GND7")
		(2 "B.Cu" signal "BOTTOM")
		(9 "F.Adhes" user "F.Adhesive")
		(11 "B.Adhes" user "B.Adhesive")
		(13 "F.Paste" user "Package Geometry/Pastemask Top")
		(15 "B.Paste" user "Package Geometry/Pastemask Bottom")
		(5 "F.SilkS" user "Ref Des/Silkscreen Top")
		(7 "B.SilkS" user "Ref Des/Silkscreen Bottom")
		(1 "F.Mask" user "Board Geometry/Soldermask Top")
		(3 "B.Mask" user "Board Geometry/Soldermask Bottom")
		(17 "Dwgs.User" user "User.Drawings")
		(19 "Cmts.User" user "User.Comments")
		(21 "Eco1.User" user "User.Eco1")
		(23 "Eco2.User" user "User.Eco2")
		(25 "Edge.Cuts" user "Board Geometry/Outline")
		(27 "Margin" user)
		(31 "F.CrtYd" user "Package Geometry/Place Bound Top")
		(29 "B.CrtYd" user "Package Geometry/Place Bound Bottom")
		(35 "F.Fab" user "Ref Des/Assembly Top")
		(33 "B.Fab" user "Ref Des/Assembly Bottom")
	)
	(footprint ""
		(layer "F.Cu")
		(at 357.50881 -402.7424 -90)
		(property "Reference" "R1043"
			(at 0 0 270)
			(layer "F.SilkS")
			(hide yes)
			(effects
				(font
					(size 1.27 1.27)
				)
			)
		)
		(property "Value" ""
			(at 0 0 270)
			(layer "F.Fab")
			(effects
				(font
					(size 1.27 1.27)
				)
			)
		)
		(duplicate_pad_numbers_are_jumpers no)
		(fp_line
			(start -0.32512 0.175006)
			(end -0.32512 -0.175006)
			(stroke
				(width 0.1)
				(type default)
			)
			(layer "F.Fab")
		)
		(fp_line
			(start 0.32512 0.175006)
			(end -0.32512 0.175006)
			(stroke
				(width 0.1)
				(type default)
			)
			(layer "F.Fab")
		)
		(fp_line
			(start -0.32512 -0.175006)
			(end 0.32512 -0.175006)
			(stroke
				(width 0.1)
				(type default)
			)
			(layer "F.Fab")
		)
		(fp_line
			(start 0.32512 -0.175006)
			(end 0.32512 0.175006)
			(stroke
				(width 0.1)
				(type default)
			)
			(layer "F.Fab")
		)
		(pad "1" smd rect
			(at -0.2667 0 270)
			(size 0.3048 0.381)
			(layers "F.Cu" "F.Mask" "F.Paste")
			(net "NCF_A1_CPU0_P1_GND")
		)
		(pad "2" smd rect
			(at 0.2667 0 90)
			(size 0.3048 0.381)
			(layers "F.Cu" "F.Mask" "F.Paste")
			(net "GND")
		)
	)
	(footprint ""
		(layer "F.Cu")
		(at 204.7621 -405.036782 180)
		(property "Reference" "PC2185"
			(at 0 0 180)
			(layer "F.SilkS")
			(hide yes)
			(effects
				(font
					(size 1.27 1.27)
				)
			)
		)
		(property "Value" ""
			(at 0 0 180)
			(layer "F.Fab")
			(effects
				(font
					(size 1.27 1.27)
				)
			)
		)
		(duplicate_pad_numbers_are_jumpers no)
		(fp_line
			(start 0.7874 0.4064)
			(end -0.7874 0.4064)
			(stroke
				(width 0.1524)
				(type default)
			)
			(layer "F.SilkS")
		)
		(fp_line
			(start 0.7874 -0.4064)
			(end 0.7874 0.4064)
			(stroke
				(width 0.1524)
				(type default)
			)
			(layer "F.SilkS")
		)
		(fp_line
			(start -0.7874 0.4064)
			(end -0.7874 -0.4064)
			(stroke
				(width 0.1524)
				(type default)
			)
			(layer "F.SilkS")
		)
		(fp_line
			(start -0.7874 -0.4064)
			(end 0.7874 -0.4064)
			(stroke
				(width 0.1524)
				(type default)
			)
			(layer "F.SilkS")
		)
		(fp_line
			(start 0.67945 0.3048)
			(end 0.120396 0.3048)
			(stroke
				(width 0.1)
				(type default)
			)
			(layer "F.Fab")
		)
		(fp_line
			(start 0.67945 -0.3048)
			(end 0.67945 0.3048)
			(stroke
				(width 0.1)
				(type default)
			)
			(layer "F.Fab")
		)
		(fp_line
			(start 0.12065 -0.2794)
			(end 0.12065 -0.3048)
			(stroke
				(width 0.1)
				(type default)
			)
			(layer "F.Fab")
		)
		(fp_line
			(start 0.12065 -0.3048)
			(end 0.67945 -0.3048)
			(stroke
				(width 0.1)
				(type default)
			)
			(layer "F.Fab")
		)
		(fp_line
			(start 0.120396 0.3048)
			(end 0.120396 0.2794)
			(stroke
				(width 0.1)
				(type default)
			)
			(layer "F.Fab")
		)
		(fp_line
			(start 0.120396 0.2794)
			(end -0.12065 0.2794)
			(stroke
				(width 0.1)
				(type default)
			)
			(layer "F.Fab")
		)
		(fp_line
			(start -0.12065 0.3048)
			(end -0.67945 0.3048)
			(stroke
				(width 0.1)
				(type default)
			)
			(layer "F.Fab")
		)
		(fp_line
			(start -0.12065 0.2794)
			(end -0.12065 0.3048)
			(stroke
				(width 0.1)
				(type default)
			)
			(layer "F.Fab")
		)
		(fp_line
			(start -0.12065 -0.2794)
			(end 0.12065 -0.2794)
			(stroke
				(width 0.1)
				(type default)
			)
			(layer "F.Fab")
		)
		(fp_line
			(start -0.12065 -0.305054)
			(end -0.12065 -0.2794)
			(stroke
				(width 0.1)
				(type default)
			)
			(layer "F.Fab")
		)
		(fp_line
			(start -0.67945 0.3048)
			(end -0.67945 -0.305054)
			(stroke
				(width 0.1)
				(type default)
			)
			(layer "F.Fab")
		)
		(fp_line
			(start -0.67945 -0.305054)
			(end -0.12065 -0.305054)
			(stroke
				(width 0.1)
				(type default)
			)
			(layer "F.Fab")
		)
		(pad "1" smd circle
			(at -0.40005 0 180)
			(size 0 0)
			(layers "F.Cu" "F.Mask" "F.Paste")
			(net "HSC_SS")
		)
		(pad "2" smd circle
			(at 0.40005 0 180)
			(size 0 0)
			(layers "F.Cu" "F.Mask" "F.Paste")
			(net "AGND_HSC")
		)
	)
	(footprint ""
		(layer "F.Cu")
		(at 174.625 -100.294948 90)
		(property "Reference" "R10"
			(at 0 0 90)
			(layer "F.SilkS")
			(hide yes)
			(effects
				(font
					(size 1.27 1.27)
				)
			)
		)
		(property "Value" ""
			(at 0 0 90)
			(layer "F.Fab")
			(effects
				(font
					(size 1.27 1.27)
				)
			)
		)
		(duplicate_pad_numbers_are_jumpers no)
		(fp_line
			(start 0.7874 -0.4064)
			(end 0.7874 0.4064)
			(stroke
				(width 0.1524)
				(type default)
			)
			(layer "F.SilkS")
		)
		(fp_line
			(start -0.7874 -0.4064)
			(end 0.7874 -0.4064)
			(stroke
				(width 0.1524)
				(type default)
			)
			(layer "F.SilkS")
		)
		(fp_line
			(start 0.7874 0.4064)
			(end -0.7874 0.4064)
			(stroke
				(width 0.1524)
				(type default)
			)
			(layer "F.SilkS")
		)
		(fp_line
			(start -0.7874 0.4064)
			(end -0.7874 -0.4064)
			(stroke
				(width 0.1524)
				(type default)
			)
			(layer "F.SilkS")
		)
		(fp_line
			(start -0.12065 -0.305054)
			(end -0.12065 -0.2794)
			(stroke
				(width 0.1)
				(type default)
			)
			(layer "F.Fab")
		)
		(fp_line
			(start -0.67945 -0.305054)
			(end -0.12065 -0.305054)
			(stroke
				(width 0.1)
				(type default)
			)
			(layer "F.Fab")
		)
		(fp_line
			(start 0.67945 -0.3048)
			(end 0.67945 0.3048)
			(stroke
				(width 0.1)
				(type default)
			)
			(layer "F.Fab")
		)
		(fp_line
			(start 0.12065 -0.3048)
			(end 0.67945 -0.3048)
			(stroke
				(width 0.1)
				(type default)
			)
			(layer "F.Fab")
		)
		(fp_line
			(start 0.12065 -0.2794)
			(end 0.12065 -0.3048)
			(stroke
				(width 0.1)
				(type default)
			)
			(layer "F.Fab")
		)
		(fp_line
			(start -0.12065 -0.2794)
			(end 0.12065 -0.2794)
			(stroke
				(width 0.1)
				(type default)
			)
			(layer "F.Fab")
		)
		(fp_line
			(start 0.120396 0.2794)
			(end -0.12065 0.2794)
			(stroke
				(width 0.1)
				(type default)
			)
			(layer "F.Fab")
		)
		(fp_line
			(start -0.12065 0.2794)
			(end -0.12065 0.3048)
			(stroke
				(width 0.1)
				(type default)
			)
			(layer "F.Fab")
		)
		(fp_line
			(start 0.67945 0.3048)
			(end 0.120396 0.3048)
			(stroke
				(width 0.1)
				(type default)
			)
			(layer "F.Fab")
		)
		(fp_line
			(start 0.120396 0.3048)
			(end 0.120396 0.2794)
			(stroke
				(width 0.1)
				(type default)
			)
			(layer "F.Fab")
		)
		(fp_line
			(start -0.12065 0.3048)
			(end -0.67945 0.3048)
			(stroke
				(width 0.1)
				(type default)
			)
			(layer "F.Fab")
		)
		(fp_line
			(start -0.67945 0.3048)
			(end -0.67945 -0.305054)
			(stroke
				(width 0.1)
				(type default)
			)
			(layer "F.Fab")
		)
		(pad "1" smd circle
			(at -0.40005 0 90)
			(size 0 0)
			(layers "F.Cu" "F.Mask" "F.Paste")
			(net "FM_I3C_CPU0_MUX0_OE_N")
		)
		(pad "2" smd circle
			(at 0.40005 0 90)
			(size 0 0)
			(layers "F.Cu" "F.Mask" "F.Paste")
			(net "GND")
		)
	)
)
